G04*
G04 #@! TF.GenerationSoftware,Altium Limited,Altium Designer,23.7.1 (13)*
G04*
G04 Layer_Color=16711935*
%FSLAX25Y25*%
%MOIN*%
G70*
G04*
G04 #@! TF.SameCoordinates,AF00DCEB-AC48-4C7C-91EA-99F42E284231*
G04*
G04*
G04 #@! TF.FilePolarity,Positive*
G04*
G01*
G75*
%ADD18C,0.01000*%
%ADD19C,0.00600*%
%ADD23C,0.00394*%
D18*
X624016Y-257579D02*
X620080D01*
Y-255611D01*
X620736Y-254955D01*
X622048D01*
X622704Y-255611D01*
Y-257579D01*
X620736Y-251019D02*
X620080Y-251675D01*
Y-252987D01*
X620736Y-253643D01*
X623360D01*
X624016Y-252987D01*
Y-251675D01*
X623360Y-251019D01*
X620080Y-249707D02*
X624016D01*
Y-247739D01*
X623360Y-247083D01*
X622704D01*
X622048Y-247739D01*
Y-249707D01*
Y-247739D01*
X621392Y-247083D01*
X620736D01*
X620080Y-247739D01*
Y-249707D01*
Y-239212D02*
Y-241836D01*
X624016D01*
Y-239212D01*
X622048Y-241836D02*
Y-240524D01*
X620080Y-237900D02*
X624016D01*
Y-235932D01*
X623360Y-235276D01*
X620736D01*
X620080Y-235932D01*
Y-237900D01*
X620736Y-231341D02*
X620080Y-231996D01*
Y-233308D01*
X620736Y-233964D01*
X623360D01*
X624016Y-233308D01*
Y-231996D01*
X623360Y-231341D01*
X622048D01*
Y-232652D01*
X620080Y-227405D02*
Y-230029D01*
X624016D01*
Y-227405D01*
X622048Y-230029D02*
Y-228717D01*
D19*
X384615Y-241552D02*
X387948D01*
X388614Y-240885D01*
Y-239553D01*
X387948Y-238886D01*
X384615D01*
X388614Y-234888D02*
Y-237553D01*
X385948Y-234888D01*
X385282D01*
X384615Y-235554D01*
Y-236887D01*
X385282Y-237553D01*
X384615Y-233555D02*
Y-230889D01*
X385282D01*
X387948Y-233555D01*
X388614D01*
D23*
X148622Y-372195D02*
G03*
X134252Y-372195I-7185J0D01*
G01*
X200197Y-385876D02*
G03*
X192717Y-385876I-3740J0D01*
G01*
X200197D02*
G03*
X192717Y-385876I-3740J0D01*
G01*
X148622Y-372195D02*
G03*
X134252Y-372195I-7185J0D01*
G01*
X625787Y-301673D02*
Y-258366D01*
X629528Y-48444D02*
Y23108D01*
Y-48444D02*
X630958Y-49875D01*
X629528Y23108D02*
X630244Y22392D01*
X630958Y-366733D02*
Y-49875D01*
X-28543Y22392D02*
X630244D01*
X213832Y-366733D02*
X630958D01*
X-28543Y-397490D02*
Y22392D01*
Y-397490D02*
X30512D01*
Y-365009D01*
X102756D01*
Y-397490D02*
Y-365009D01*
Y-397490D02*
X134252D01*
Y-372195D01*
X148622Y-413238D02*
Y-372195D01*
X150591Y-415206D02*
X190748D01*
X202165D02*
X281693D01*
X283661Y-413238D02*
Y-365009D01*
X148622Y-413238D02*
X150591Y-415206D01*
X190748D02*
X192717Y-413238D01*
X200197D02*
X202165Y-415206D01*
X281693D02*
X283661Y-413238D01*
X192717D02*
Y-385876D01*
X200197Y-413238D02*
Y-385876D01*
M02*
